(kicad_pcb
	(version 20260206)
	(generator "pcbnew")
	(generator_version "10.0")
	(general
		(thickness 1.6)
		(legacy_teardrops no)
	)
	(paper "A4")
	(title_block
		(title "Wiwynn_Tioga_Pass_MB.brd")
		(comment 1 "Tioga Pass / footprint 368 of 4770 (J9B3), pads 118-122 of 122")
	)
	(layers
		(0 "F.Cu" signal "TOP")
		(4 "In1.Cu" signal "L2GND")
		(6 "In2.Cu" signal "L3")
		(8 "In3.Cu" signal "L4GND")
		(10 "In4.Cu" signal "L5")
		(12 "In5.Cu" signal "L6GND")
		(14 "In6.Cu" signal "L7VCC")
		(16 "In7.Cu" signal "L8VCC")
		(18 "In8.Cu" signal "L9GND")
		(20 "In9.Cu" signal "L10")
		(22 "In10.Cu" signal "L11GND")
		(24 "In11.Cu" signal "L12")
		(26 "In12.Cu" signal "L13GND")
		(2 "B.Cu" signal "BOTTOM")
		(9 "F.Adhes" user "F.Adhesive")
		(11 "B.Adhes" user "B.Adhesive")
		(13 "F.Paste" user "Package Geometry/Pastemask Top")
		(15 "B.Paste" user "Package Geometry/Pastemask Bottom")
		(5 "F.SilkS" user "Ref Des/Silkscreen Top")
		(7 "B.SilkS" user "Ref Des/Silkscreen Bottom")
		(1 "F.Mask" user "Board Geometry/Soldermask Top")
		(3 "B.Mask" user "Board Geometry/Soldermask Bottom")
		(17 "Dwgs.User" user "User.Drawings")
		(19 "Cmts.User" user "User.Comments")
		(21 "Eco1.User" user "User.Eco1")
		(23 "Eco2.User" user "User.Eco2")
		(25 "Edge.Cuts" user "Board Geometry/Outline")
		(27 "Margin" user)
		(31 "F.CrtYd" user "Package Geometry/Place Bound Top")
		(29 "B.CrtYd" user "Package Geometry/Place Bound Bottom")
		(35 "F.Fab" user "Ref Des/Assembly Top")
		(33 "B.Fab" user "Ref Des/Assembly Bottom")
	)
	(footprint ""
		(layer "F.Cu")
		(at 487.800904 -116.993162 -90)
		(property "Reference" "J9B3"
			(at -2.227072 26.281888 0)
			(unlocked yes)
			(layer "F.SilkS")
			(effects
				(font
					(size 0.7874 0.5842)
					(thickness 0.1524)
				)
			)
		)
		(property "Value" ""
			(at 0 0 270)
			(layer "F.Fab")
			(effects
				(font
					(size 1.27 1.27)
				)
			)
		)
		(duplicate_pad_numbers_are_jumpers no)
		(pad "116" smd rect
			(at 4.787646 45.600112 270)
			(size 2.3876 0.508)
			(layers "F.Cu" "F.Mask" "F.Paste")
			(net "GND")
		)
		(pad "117" smd rect
			(at 0 46.399958 270)
			(size 2.3876 0.508)
			(layers "F.Cu" "F.Mask" "F.Paste")
			(net "P3E_CPU0_PE3_OCP_RXN<8>")
		)
		(pad "118" smd rect
			(at 4.787646 46.399958 270)
			(size 2.3876 0.508)
			(layers "F.Cu" "F.Mask" "F.Paste")
			(net "GND")
		)
		(pad "119" smd rect
			(at 0 47.200058 270)
			(size 2.3876 0.508)
			(layers "F.Cu" "F.Mask" "F.Paste")
			(net "GND")
		)
		(pad "120" smd rect
			(at 4.787646 47.200058 270)
			(size 2.3876 0.508)
			(layers "F.Cu" "F.Mask" "F.Paste")
			(net "FM_OCP_MEZZA_PRES_N")
		)
	)
)
